# T6G (Grand Teton) — schematic netlist excerpt (pin names and nets, part order shuffled) for the footprints in the layout excerpt that follows; sources: Cadence DE-HDL packaged netlist, KiCad conversion of 04192023_DAF0TMB3IC0_F0TG_MB_C_brd_V02_OCP.brd

J32  SCONN288_DDR506112002KQ  IO  pkg DDR288S_1-1VXC  page 102
  VIN_BULK0  = P12V_MEM_CPU1
  RFU0  = NC
  VIN_MGMT  = P3V3_AUX
  HSCL  = I3C_SPD_DDRE_CPU1_SCL
  HSDA  = I3C_SPD_DDRE_CPU1_SDA
  VSS0  = GND
  DQ0_A  = M_E_CPU1_SA_DQ<0>
  VSS1  = GND
  DQ1_A  = M_E_CPU1_SA_DQ<1>
  VSS2  = GND
  DQS0_A_T  = M_E_CPU1_SA_DQS_DP<0>
  DQS0_A_C  = M_E_CPU1_SA_DQS_DN<0>
  VSS3  = GND
  DQ4_A  = M_E_CPU1_SA_DQ<4>
  VSS4  = GND
  DQ5_A  = M_E_CPU1_SA_DQ<5>
  VSS5  = GND
  DQ8_A  = M_E_CPU1_SA_DQ<8>
  VSS6  = GND
  DQ9_A  = M_E_CPU1_SA_DQ<9>
  VSS7  = GND
  DQS1_A_T  = M_E_CPU1_SA_DQS_DP<1>
  DQS1_A_C  = M_E_CPU1_SA_DQS_DN<1>
  VSS8  = GND
  DQ12_A  = M_E_CPU1_SA_DQ<12>
  VSS9  = GND
  DQ13_A  = M_E_CPU1_SA_DQ<13>
  VSS10  = GND
  DQ16_A  = M_E_CPU1_SA_DQ<16>
  VSS11  = GND
  DQ17_A  = M_E_CPU1_SA_DQ<17>
  VSS12  = GND
  DQS2_A_T  = M_E_CPU1_SA_DQS_DP<2>
  DQS2_A_C  = M_E_CPU1_SA_DQS_DN<2>
  VSS13  = GND
  DQ20_A  = M_E_CPU1_SA_DQ<20>
  VSS14  = GND
  DQ21_A  = M_E_CPU1_SA_DQ<21>
  VSS15  = GND
  DQ24_A  = M_E_CPU1_SA_DQ<24>
  VSS16  = GND
  DQ25_A  = M_E_CPU1_SA_DQ<25>
  VSS17  = GND
  DQS3_A_T  = M_E_CPU1_SA_DQS_DP<3>
  DQS3_A_C  = M_E_CPU1_SA_DQS_DN<3>
  VSS18  = GND
  DQ28_A  = M_E_CPU1_SA_DQ<28>
  VSS19  = GND
  DQ29_A  = M_E_CPU1_SA_DQ<29>
  VSS20  = GND
  CB0_A  = M_E_CPU1_SA_CB<0>
  VSS21  = GND
  CB1_A  = M_E_CPU1_SA_CB<1>
  VSS22  = GND
  DQS4_A_T  = M_E_CPU1_SA_DQS_DP<4>
  DQS4_A_C  = M_E_CPU1_SA_DQS_DN<4>
  VSS23  = GND
  CB4_A  = M_E_CPU1_SA_CB<4>
  VSS24  = GND
  CB5_A  = M_E_CPU1_SA_CB<5>
  VSS25  = GND
  ALERT_N  = M_E_CPU1_ALERT_N
  VSS26  = GND
  CS0_A_N  = M_E_CPU1_SA_CS_N<0>
  VSS27  = GND
  CA0_A  = M_E_CPU1_SA_CA<0>
  VSS28  = GND
  CA2_A  = M_E_CPU1_SA_CA<2>
  VSS29  = GND
  CA4_A  = M_E_CPU1_SA_CA<4>
  VSS30  = GND
  CA6_A  = M_E_CPU1_SA_CA<6>
  VSS31  = GND
  PAR_A  = M_E_CPU1_SA_PAR
  VSS32  = GND
  CA0_B  = M_E_CPU1_SB_CA<0>
  VSS33  = GND
  CA2_B  = M_E_CPU1_SB_CA<2>
  VSS34  = GND
  CA4_B  = M_E_CPU1_SB_CA<4>
  VSS35  = GND
  CA6_B  = M_E_CPU1_SB_CA<6>
  VSS36  = GND
  CS0_B_N  = M_E_CPU1_SB_CS_N<0>
  VSS37  = GND
  \lbd||rsp_a_n\  = M_E_CPU1_SA_RSP<0>
  \lbs||rsp_b_n\  = M_E_CPU1_SB_RSP<0>
  VSS38  = GND
  CB4_B  = M_E_CPU1_SB_CB<4>
  VSS39  = GND
  CB5_B  = M_E_CPU1_SB_CB<5>
  VSS40  = GND
  \dqs9_b_t||tdqs9_b_t||dbi4_b_n\  = M_E_CPU1_SB_DQS_DP<9>
  \dqs9_b_c||tdqs9_b_c\  = M_E_CPU1_SB_DQS_DN<9>
  VSS41  = GND
  CB0_B  = M_E_CPU1_SB_CB<0>
  VSS42  = GND
  CB1_B  = M_E_CPU1_SB_CB<1>
  VSS43  = GND
  DQ0_B  = M_E_CPU1_SB_DQ<0>
  VSS44  = GND
  DQ1_B  = M_E_CPU1_SB_DQ<1>
  VSS45  = GND
  DQS0_B_T  = M_E_CPU1_SB_DQS_DP<0>
  DQS0_B_C  = M_E_CPU1_SB_DQS_DN<0>
  VSS46  = GND
  DQ4_B  = M_E_CPU1_SB_DQ<4>
  VSS47  = GND
  DQ5_B  = M_E_CPU1_SB_DQ<5>
  VSS48  = GND
  DQ8_B  = M_E_CPU1_SB_DQ<8>
  VSS49  = GND
  DQ9_B  = M_E_CPU1_SB_DQ<9>
  VSS50  = GND
  DQS1_B_T  = M_E_CPU1_SB_DQS_DP<1>
  DQS1_B_C  = M_E_CPU1_SB_DQS_DN<1>
  VSS51  = GND
  DQ12_B  = M_E_CPU1_SB_DQ<12>
  VSS52  = GND
  DQ13_B  = M_E_CPU1_SB_DQ<13>
  VSS53  = GND
  DQ16_B  = M_E_CPU1_SB_DQ<16>
  VSS54  = GND
  DQ17_B  = M_E_CPU1_SB_DQ<17>
  VSS55  = GND
  DQS2_B_T  = M_E_CPU1_SB_DQS_DP<2>
  DQS2_B_C  = M_E_CPU1_SB_DQS_DN<2>
  VSS56  = GND
  DQ20_B  = M_E_CPU1_SB_DQ<20>
  VSS57  = GND
  DQ21_B  = M_E_CPU1_SB_DQ<21>
  VSS58  = GND
  DQ24_B  = M_E_CPU1_SB_DQ<24>
  VSS59  = GND
  DQ25_B  = M_E_CPU1_SB_DQ<25>
  VSS60  = GND
  DQS3_B_T  = M_E_CPU1_SB_DQS_DP<3>
  DQS3_B_C  = M_E_CPU1_SB_DQS_DN<3>
  VSS61  = GND
  DQ28_B  = M_E_CPU1_SB_DQ<28>
  VSS62  = GND
  DQ29_B  = M_E_CPU1_SB_DQ<29>
  VSS63  = GND
  RFU1  = NC
  VIN_BULK1  = P12V_MEM_CPU1
  VIN_BULK2  = P12V_MEM_CPU1
  \pwr_good||fail_n\  = PWRGD_CHE_CPU1_DIMM
  HAS  = PD_CHE_CPU1_DIMM_SAA
  RFU2  = NC
  RFU3  = NC
  VSS64  = GND
  DQ2_A  = M_E_CPU1_SA_DQ<2>
  VSS65  = GND
  DQ3_A  = M_E_CPU1_SA_DQ<3>
  VSS66  = GND
  \dqs5_a_c||tdqs5_a_c||dqs5_a_t||tdqs5_a_t\  = M_E_CPU1_SA_DQS_DN<5>
  \dqs5_a_t||tdqs5_a_t\  = M_E_CPU1_SA_DQS_DP<5>
  VSS67  = GND
  DQ6_A  = M_E_CPU1_SA_DQ<6>
  VSS68  = GND
  DQ7_A  = M_E_CPU1_SA_DQ<7>
  VSS69  = GND
  DQ10_A  = M_E_CPU1_SA_DQ<10>
  VSS70  = GND
  DQ11_A  = M_E_CPU1_SA_DQ<11>
  VSS71  = GND
  \dqs6_a_c||tdqs6_a_c||dqs6_a_t||tdqs6_a_t\  = M_E_CPU1_SA_DQS_DN<6>
  \dqs6_a_t||tdqs6_a_t\  = M_E_CPU1_SA_DQS_DP<6>
  VSS72  = GND
  DQ14_A  = M_E_CPU1_SA_DQ<14>
  VSS73  = GND
  DQ15_A  = M_E_CPU1_SA_DQ<15>
  VSS74  = GND
  DQ18_A  = M_E_CPU1_SA_DQ<18>
  VSS75  = GND
  DQ19_A  = M_E_CPU1_SA_DQ<19>
  VSS76  = GND
  \dqs7_a_c||tdqs7_a_c\  = M_E_CPU1_SA_DQS_DN<7>
  \dqs7_a_t||tdqs7_a_t\  = M_E_CPU1_SA_DQS_DP<7>
  VSS77  = GND
  DQ22_A  = M_E_CPU1_SA_DQ<22>
  VSS78  = GND
  DQ23_A  = M_E_CPU1_SA_DQ<23>
  VSS79  = GND
  DQ26_A  = M_E_CPU1_SA_DQ<26>
  VSS80  = GND
  DQ27_A  = M_E_CPU1_SA_DQ<27>
  VSS81  = GND
  \dqs8_a_c||tdqs8_a_c\  = M_E_CPU1_SA_DQS_DN<8>
  \dqs8_a_t||tdqs8_a_t\  = M_E_CPU1_SA_DQS_DP<8>
  VSS82  = GND
  DQ30_A  = M_E_CPU1_SA_DQ<30>
  VSS83  = GND
  DQ31_A  = M_E_CPU1_SA_DQ<31>
  VSS84  = GND
  CB2_A  = M_E_CPU1_SA_CB<2>
  VSS85  = GND
  CB3_A  = M_E_CPU1_SA_CB<3>
  VSS86  = GND
  \dqs9_a_c||tdqs9_a_c\  = M_E_CPU1_SA_DQS_DN<9>
  \dqs9_a_t||tdqs9_a_t\  = M_E_CPU1_SA_DQS_DP<9>
  VSS87  = GND
  CB6_A  = M_E_CPU1_SA_CB<6>
  VSS88  = GND
  CB7_A  = M_E_CPU1_SA_CB<7>
  VSS89  = GND
  RESET_N  = M_E_CPU1_RESET_N
  VSS90  = GND
  CS1_A_N  = M_E_CPU1_SA_CS_N<1>
  VSS91  = GND
  CA1_A  = M_E_CPU1_SA_CA<1>
  VSS92  = GND
  CA3_A  = M_E_CPU1_SA_CA<3>
  VSS93  = GND
  CA5_A  = M_E_CPU1_SA_CA<5>
  VSS94  = GND
  CK_T  = M_E_CPU1_CLK_DP<0>
  CK_C  = M_E_CPU1_CLK_DN<0>
  VSS95  = GND
  RFU4  = NC
  CA1_B  = M_E_CPU1_SB_CA<1>
  VSS96  = GND
  CA3_B  = M_E_CPU1_SB_CA<3>
  VSS97  = GND
  CA5_B  = M_E_CPU1_SB_CA<5>
  VSS98  = GND
  PAR_B  = M_E_CPU1_SB_PAR
  VSS99  = GND
  CS1_B_N  = M_E_CPU1_SB_CS_N<1>
  VSS100  = GND
  RFU5  = NC
  RFU6  = NC
  VSS101  = GND
  CB6_B  = M_E_CPU1_SB_CB<6>
  VSS102  = GND
  CB7_B  = M_E_CPU1_SB_CB<7>
  VSS103  = GND
  DQS4_B_C  = M_E_CPU1_SB_DQS_DN<4>
  DQS4_B_T  = M_E_CPU1_SB_DQS_DP<4>
  VSS104  = GND
  CB2_B  = M_E_CPU1_SB_CB<2>
  VSS105  = GND
  CB3_B  = M_E_CPU1_SB_CB<3>
  VSS106  = GND
  DQ2_B  = M_E_CPU1_SB_DQ<2>
  VSS107  = GND
  DQ3_B  = M_E_CPU1_SB_DQ<3>
  VSS108  = GND
  \dqs5_b_c||tdqs5_b_c\  = M_E_CPU1_SB_DQS_DN<5>
  \dqs5_b_t||tdqs5_b_t\  = M_E_CPU1_SB_DQS_DP<5>
  VSS109  = GND
  DQ6_B  = M_E_CPU1_SB_DQ<6>
  VSS110  = GND
  DQ7_B  = M_E_CPU1_SB_DQ<7>
  VSS111  = GND
  DQ10_B  = M_E_CPU1_SB_DQ<10>
  VSS112  = GND
  DQ11_B  = M_E_CPU1_SB_DQ<11>
  VSS113  = GND
  \dqs6_b_c||tdqs6_b_c\  = M_E_CPU1_SB_DQS_DN<6>
  \dqs6_b_t||tdqs6_b_t\  = M_E_CPU1_SB_DQS_DP<6>
  VSS114  = GND
  DQ14_B  = M_E_CPU1_SB_DQ<14>
  VSS115  = GND
  DQ15_B  = M_E_CPU1_SB_DQ<15>
  VSS116  = GND
  DQ18_B  = M_E_CPU1_SB_DQ<18>
  VSS117  = GND
  DQ19_B  = M_E_CPU1_SB_DQ<19>
  VSS118  = GND
  \dqs7_b_c||tdqs7_b_c\  = M_E_CPU1_SB_DQS_DN<7>
  \dqs7_b_t||tdqs7_b_t\  = M_E_CPU1_SB_DQS_DP<7>
  VSS119  = GND
  DQ22_B  = M_E_CPU1_SB_DQ<22>
  VSS120  = GND
  DQ23_B  = M_E_CPU1_SB_DQ<23>
  VSS121  = GND
  DQ26_B  = M_E_CPU1_SB_DQ<26>
  VSS122  = GND
  DQ27_B  = M_E_CPU1_SB_DQ<27>
  VSS123  = GND
  \dqs8_b_c||tdqs8_b_c\  = M_E_CPU1_SB_DQS_DN<8>
  \dqs8_b_t||tdqs8_b_t\  = M_E_CPU1_SB_DQS_DP<8>
  VSS124  = GND
  DQ30_B  = M_E_CPU1_SB_DQ<30>
  VSS125  = GND
  DQ31_B  = M_E_CPU1_SB_DQ<31>
  VSS126  = GND
  G1  = GND
  G2  = GND
  G3  = GND

(kicad_pcb
	(version 20260206)
	(generator "pcbnew")
	(generator_version "10.0")
	(general
		(thickness 1.6)
		(legacy_teardrops no)
	)
	(paper "A4")
	(title_block
		(title "04192023_DAF0TMB3IC0_F0TG_MB_C_brd_V02_OCP.brd")
		(comment 1 "Grand Teton / footprint 4612 of 8354 (J32), pads 277-291 of 291")
	)
	(layers
		(0 "F.Cu" signal "TOP")
		(4 "In1.Cu" signal "GND")
		(6 "In2.Cu" signal "IN1")
		(8 "In3.Cu" signal "GND1")
		(10 "In4.Cu" signal "IN2")
		(12 "In5.Cu" signal "GND2")
		(14 "In6.Cu" signal "IN3")
		(16 "In7.Cu" signal "GND3")
		(18 "In8.Cu" signal "VCC")
		(20 "In9.Cu" signal "VCC1")
		(22 "In10.Cu" signal "GND4")
		(24 "In11.Cu" signal "IN4")
		(26 "In12.Cu" signal "GND5")
		(28 "In13.Cu" signal "IN5")
		(30 "In14.Cu" signal "GND6")
		(32 "In15.Cu" signal "IN6")
		(34 "In16.Cu" signal "GND7")
		(2 "B.Cu" signal "BOTTOM")
		(9 "F.Adhes" user "F.Adhesive")
		(11 "B.Adhes" user "B.Adhesive")
		(13 "F.Paste" user "Package Geometry/Pastemask Top")
		(15 "B.Paste" user "Package Geometry/Pastemask Bottom")
		(5 "F.SilkS" user "Ref Des/Silkscreen Top")
		(7 "B.SilkS" user "Ref Des/Silkscreen Bottom")
		(1 "F.Mask" user "Board Geometry/Soldermask Top")
		(3 "B.Mask" user "Board Geometry/Soldermask Bottom")
		(17 "Dwgs.User" user "User.Drawings")
		(19 "Cmts.User" user "User.Comments")
		(21 "Eco1.User" user "User.Eco1")
		(23 "Eco2.User" user "User.Eco2")
		(25 "Edge.Cuts" user "Board Geometry/Outline")
		(27 "Margin" user)
		(31 "F.CrtYd" user "Package Geometry/Place Bound Top")
		(29 "B.CrtYd" user "Package Geometry/Place Bound Bottom")
		(35 "F.Fab" user "Ref Des/Assembly Top")
		(33 "B.Fab" user "Ref Des/Assembly Bottom")
	)
	(footprint ""
		(layer "F.Cu")
		(at 27.20213 -255.560322 180)
		(property "Reference" "J32"
			(at 1.80086 -81.974436 0)
			(unlocked yes)
			(layer "F.SilkS")
			(effects
				(font
					(size 0.7874 0.5842)
					(thickness 0.1524)
				)
			)
		)
		(property "Value" ""
			(at 0 0 180)
			(layer "F.Fab")
			(effects
				(font
					(size 1.27 1.27)
				)
			)
		)
		(duplicate_pad_numbers_are_jumpers no)
		(pad "277" smd rect
			(at 2.050034 53.975 90)
			(size 0.519938 1.4986)
			(layers "F.Cu" "F.Mask" "F.Paste")
			(net "GND")
		)
		(pad "278" smd rect
			(at 2.050034 54.824884 90)
			(size 0.519938 1.4986)
			(layers "F.Cu" "F.Mask" "F.Paste")
			(net "M_E_CPU1_SB_DQ<26>")
		)
		(pad "279" smd rect
			(at 2.050034 55.675022 90)
			(size 0.519938 1.4986)
			(layers "F.Cu" "F.Mask" "F.Paste")
			(net "GND")
		)
		(pad "280" smd rect
			(at 2.050034 56.524906 90)
			(size 0.519938 1.4986)
			(layers "F.Cu" "F.Mask" "F.Paste")
			(net "M_E_CPU1_SB_DQ<27>")
		)
		(pad "281" smd rect
			(at 2.050034 57.375044 90)
			(size 0.519938 1.4986)
			(layers "F.Cu" "F.Mask" "F.Paste")
			(net "GND")
		)
		(pad "282" smd rect
			(at 2.050034 58.224928 90)
			(size 0.519938 1.4986)
			(layers "F.Cu" "F.Mask" "F.Paste")
			(net "M_E_CPU1_SB_DQS_DN<8>")
		)
		(pad "283" smd rect
			(at 2.050034 59.075066 90)
			(size 0.519938 1.4986)
			(layers "F.Cu" "F.Mask" "F.Paste")
			(net "M_E_CPU1_SB_DQS_DP<8>")
		)
		(pad "284" smd rect
			(at 2.050034 59.92495 90)
			(size 0.519938 1.4986)
			(layers "F.Cu" "F.Mask" "F.Paste")
			(net "GND")
		)
		(pad "285" smd rect
			(at 2.050034 60.775088 90)
			(size 0.519938 1.4986)
			(layers "F.Cu" "F.Mask" "F.Paste")
			(net "M_E_CPU1_SB_DQ<30>")
		)
		(pad "286" smd rect
			(at 2.050034 61.624972 90)
			(size 0.519938 1.4986)
			(layers "F.Cu" "F.Mask" "F.Paste")
			(net "GND")
		)
		(pad "287" smd rect
			(at 2.050034 62.47511 90)
			(size 0.519938 1.4986)
			(layers "F.Cu" "F.Mask" "F.Paste")
			(net "M_E_CPU1_SB_DQ<31>")
		)
		(pad "288" smd rect
			(at 2.050034 63.324994 90)
			(size 0.519938 1.4986)
			(layers "F.Cu" "F.Mask" "F.Paste")
			(net "GND")
		)
		(pad "G1" thru_hole oval
			(at 0 -68.97497 90)
			(size 1.7272 3.4798)
			(drill oval 1.2192 2.4638)
			(layers "*.Cu" "*.Mask")
			(remove_unused_layers no)
			(net "GND")
			(clearance 0.127)
			(thermal_gap 0.127)
		)
		(pad "G2" thru_hole oval
			(at 0 3.875024 90)
			(size 1.7272 3.4798)
			(drill oval 1.2192 2.4638)
			(layers "*.Cu" "*.Mask")
			(remove_unused_layers no)
			(net "GND")
			(clearance 0.127)
			(thermal_gap 0.127)
		)
		(pad "G3" thru_hole oval
			(at 0 68.97497 90)
			(size 1.7272 3.4798)
			(drill oval 1.2192 2.4638)
			(layers "*.Cu" "*.Mask")
			(remove_unused_layers no)
			(net "GND")
			(clearance 0.127)
			(thermal_gap 0.127)
		)
	)
)
